# T6G (Grand Teton) — schematic netlist excerpt (pin names and nets, part order shuffled) for the footprints in the layout excerpt that follows; sources: Cadence DE-HDL packaged netlist, KiCad conversion of 04192023_DAF0TMB3IC0_F0TG_MB_C_brd_V02_OCP.brd

J78  PICOPROBE_BXA  DELTA-L 4.0 EMPTY  pkg TRIANG_LAUNCH_3PXB  page 229
  \1_p\  = DELTA_L_85_10INCH_IN2_DP
  \2_n\  = DELTA_L_85_10INCH_IN2_DN
  \3_g\  = DELTA_L_GND_1

(kicad_pcb
	(version 20260206)
	(generator "pcbnew")
	(generator_version "10.0")
	(general
		(thickness 1.6)
		(legacy_teardrops no)
	)
	(paper "A4")
	(title_block
		(title "04192023_DAF0TMB3IC0_F0TG_MB_C_brd_V02_OCP.brd")
		(comment 1 "Grand Teton / footprints 2692-2692 of 8354")
	)
	(layers
		(0 "F.Cu" signal "TOP")
		(4 "In1.Cu" signal "GND")
		(6 "In2.Cu" signal "IN1")
		(8 "In3.Cu" signal "GND1")
		(10 "In4.Cu" signal "IN2")
		(12 "In5.Cu" signal "GND2")
		(14 "In6.Cu" signal "IN3")
		(16 "In7.Cu" signal "GND3")
		(18 "In8.Cu" signal "VCC")
		(20 "In9.Cu" signal "VCC1")
		(22 "In10.Cu" signal "GND4")
		(24 "In11.Cu" signal "IN4")
		(26 "In12.Cu" signal "GND5")
		(28 "In13.Cu" signal "IN5")
		(30 "In14.Cu" signal "GND6")
		(32 "In15.Cu" signal "IN6")
		(34 "In16.Cu" signal "GND7")
		(2 "B.Cu" signal "BOTTOM")
		(9 "F.Adhes" user "F.Adhesive")
		(11 "B.Adhes" user "B.Adhesive")
		(13 "F.Paste" user "Package Geometry/Pastemask Top")
		(15 "B.Paste" user "Package Geometry/Pastemask Bottom")
		(5 "F.SilkS" user "Ref Des/Silkscreen Top")
		(7 "B.SilkS" user "Ref Des/Silkscreen Bottom")
		(1 "F.Mask" user "Board Geometry/Soldermask Top")
		(3 "B.Mask" user "Board Geometry/Soldermask Bottom")
		(17 "Dwgs.User" user "User.Drawings")
		(19 "Cmts.User" user "User.Comments")
		(21 "Eco1.User" user "User.Eco1")
		(23 "Eco2.User" user "User.Eco2")
		(25 "Edge.Cuts" user "Board Geometry/Outline")
		(27 "Margin" user)
		(31 "F.CrtYd" user "Package Geometry/Place Bound Top")
		(29 "B.CrtYd" user "Package Geometry/Place Bound Bottom")
		(35 "F.Fab" user "Ref Des/Assembly Top")
		(33 "B.Fab" user "Ref Des/Assembly Bottom")
	)
	(footprint ""
		(layer "F.Cu")
		(at 212.471508 -5.077206)
		(property "Reference" "J78"
			(at -4.352036 0.945388 90)
			(unlocked yes)
			(layer "F.SilkS")
			(effects
				(font
					(size 0.7874 0.5842)
					(thickness 0.1524)
				)
				(justify left)
			)
		)
		(property "Value" ""
			(at 0 0 0)
			(layer "F.Fab")
			(effects
				(font
					(size 1.27 1.27)
				)
			)
		)
		(duplicate_pad_numbers_are_jumpers no)
		(fp_line
			(start -1.2192 -2.06756)
			(end 1.2192 -2.06756)
			(stroke
				(width 0.1524)
				(type default)
			)
			(layer "F.SilkS")
		)
		(fp_line
			(start -1.2192 2.06756)
			(end -1.2192 -2.06756)
			(stroke
				(width 0.1524)
				(type default)
			)
			(layer "F.SilkS")
		)
		(fp_line
			(start 1.2192 -2.06756)
			(end 1.2192 2.06756)
			(stroke
				(width 0.1524)
				(type default)
			)
			(layer "F.SilkS")
		)
		(fp_line
			(start 1.2192 2.06756)
			(end -1.2192 2.06756)
			(stroke
				(width 0.1524)
				(type default)
			)
			(layer "F.SilkS")
		)
		(pad "" np_thru_hole circle
			(at -2.8829 -1.27 270)
			(size 1.0414 1.0414)
			(drill 1.0414)
			(layers "*.Cu" "*.Mask")
			(clearance 0.381)
			(thermal_gap 0.381)
		)
		(pad "" np_thru_hole circle
			(at -2.8829 1.27 270)
			(size 1.0414 1.0414)
			(drill 1.0414)
			(layers "*.Cu" "*.Mask")
			(clearance 0.381)
			(thermal_gap 0.381)
		)
		(pad "" np_thru_hole circle
			(at 3.4671 -1.27 270)
			(size 1.0414 1.0414)
			(drill 1.0414)
			(layers "*.Cu" "*.Mask")
			(clearance 0.381)
			(thermal_gap 0.381)
		)
		(pad "" np_thru_hole circle
			(at 3.4671 1.27 270)
			(size 1.0414 1.0414)
			(drill 1.0414)
			(layers "*.Cu" "*.Mask")
			(clearance 0.381)
			(thermal_gap 0.381)
		)
		(pad "1" smd rect
			(at 0.8255 -0.249936 270)
			(size 0.3048 0.508)
			(layers "F.Cu" "F.Mask" "F.Paste")
			(net "DELTA_L_85_10INCH_IN2_DP")
		)
		(pad "2" smd rect
			(at 0.8255 0.249936 270)
			(size 0.3048 0.508)
			(layers "F.Cu" "F.Mask" "F.Paste")
			(net "DELTA_L_85_10INCH_IN2_DN")
		)
		(pad "3" smd circle
			(at 0 0)
			(size 0 0)
			(layers "F.Cu" "F.Mask" "F.Paste")
			(net "DELTA_L_GND_1")
		)
		(zone
			(layer "F.Cu")
			(hatch none 0.5)
			(connect_pads
				(clearance 0)
			)
			(min_thickness 0.25)
			(keepout
				(tracks not_allowed)
				(vias allowed)
				(pads allowed)
				(copperpour not_allowed)
				(footprints allowed)
			)
			(placement
				(enabled no)
				(sheetname "")
			)
			(fill
				(thermal_gap 0.5)
				(thermal_bridge_width 0.5)
				(island_removal_mode 0)
			)
			(polygon
				(pts
					(xy 213.589108 -5.625846) (xy 213.589108 -5.530342) (xy 212.992208 -5.530342) (xy 212.992208 -5.123942)
					(xy 213.589108 -5.123942) (xy 213.589108 -5.03047) (xy 212.992208 -5.03047) (xy 212.992208 -4.62407)
					(xy 213.589108 -4.62407) (xy 213.589108 -4.528566) (xy 212.890608 -4.528566) (xy 212.890608 -5.625846)
				)
			)
		)
		(zone
			(layers "F.Cu" "B.Cu" "In1.Cu" "In2.Cu" "In3.Cu" "In4.Cu" "In5.Cu" "In6.Cu"
				"In7.Cu" "In8.Cu" "In9.Cu" "In10.Cu" "In11.Cu" "In12.Cu" "In13.Cu" "In14.Cu"
				"In15.Cu" "In16.Cu"
			)
			(hatch none 0.5)
			(connect_pads
				(clearance 0)
			)
			(min_thickness 0.25)
			(keepout
				(tracks not_allowed)
				(vias allowed)
				(pads allowed)
				(copperpour not_allowed)
				(footprints allowed)
			)
			(placement
				(enabled no)
				(sheetname "")
			)
			(fill
				(thermal_gap 0.5)
				(thermal_bridge_width 0.5)
				(island_removal_mode 0)
			)
			(polygon
				(pts
					(arc
						(start 210.515708 -6.347206)
						(mid 208.661508 -6.347206)
						(end 210.515708 -6.347206)
					)
				)
			)
		)
		(zone
			(layers "F.Cu" "B.Cu" "In1.Cu" "In2.Cu" "In3.Cu" "In4.Cu" "In5.Cu" "In6.Cu"
				"In7.Cu" "In8.Cu" "In9.Cu" "In10.Cu" "In11.Cu" "In12.Cu" "In13.Cu" "In14.Cu"
				"In15.Cu" "In16.Cu"
			)
			(hatch none 0.5)
			(connect_pads
				(clearance 0)
			)
			(min_thickness 0.25)
			(keepout
				(tracks not_allowed)
				(vias allowed)
				(pads allowed)
				(copperpour not_allowed)
				(footprints allowed)
			)
			(placement
				(enabled no)
				(sheetname "")
			)
			(fill
				(thermal_gap 0.5)
				(thermal_bridge_width 0.5)
				(island_removal_mode 0)
			)
			(polygon
				(pts
					(arc
						(start 210.515708 -3.807206)
						(mid 208.661508 -3.807206)
						(end 210.515708 -3.807206)
					)
				)
			)
		)
		(zone
			(layers "F.Cu" "B.Cu" "In1.Cu" "In2.Cu" "In3.Cu" "In4.Cu" "In5.Cu" "In6.Cu"
				"In7.Cu" "In8.Cu" "In9.Cu" "In10.Cu" "In11.Cu" "In12.Cu" "In13.Cu" "In14.Cu"
				"In15.Cu" "In16.Cu"
			)
			(hatch none 0.5)
			(connect_pads
				(clearance 0)
			)
			(min_thickness 0.25)
			(keepout
				(tracks not_allowed)
				(vias allowed)
				(pads allowed)
				(copperpour not_allowed)
				(footprints allowed)
			)
			(placement
				(enabled no)
				(sheetname "")
			)
			(fill
				(thermal_gap 0.5)
				(thermal_bridge_width 0.5)
				(island_removal_mode 0)
			)
			(polygon
				(pts
					(arc
						(start 216.865708 -6.347206)
						(mid 215.011508 -6.347206)
						(end 216.865708 -6.347206)
					)
				)
			)
		)
		(zone
			(layers "F.Cu" "B.Cu" "In1.Cu" "In2.Cu" "In3.Cu" "In4.Cu" "In5.Cu" "In6.Cu"
				"In7.Cu" "In8.Cu" "In9.Cu" "In10.Cu" "In11.Cu" "In12.Cu" "In13.Cu" "In14.Cu"
				"In15.Cu" "In16.Cu"
			)
			(hatch none 0.5)
			(connect_pads
				(clearance 0)
			)
			(min_thickness 0.25)
			(keepout
				(tracks not_allowed)
				(vias allowed)
				(pads allowed)
				(copperpour not_allowed)
				(footprints allowed)
			)
			(placement
				(enabled no)
				(sheetname "")
			)
			(fill
				(thermal_gap 0.5)
				(thermal_bridge_width 0.5)
				(island_removal_mode 0)
			)
			(polygon
				(pts
					(arc
						(start 216.865708 -3.807206)
						(mid 215.011508 -3.807206)
						(end 216.865708 -3.807206)
					)
				)
			)
		)
	)
)
